# TIMECARD (Time Appliance Project (Time Card)) — schematic netlist excerpt (pin names and nets, part order shuffled) for the footprints in the layout excerpt that follows; sources: Cadence DE-HDL packaged netlist, KiCad conversion of R4006-B0001-02_R01.brd

R242  RESISTOR  150OHM 1%  pkg SMC_0402R_H016  page 15 : \1\ = OSC_125M_CLKP ; \2\ = SG
C87  CAPACITOR  18PF 5%  pkg SMC_0201R  page 24 : \1\ = SG ; \2\ = UNNAMED_524_CAPACITOR_I10_2

(kicad_pcb
	(version 20260206)
	(generator "pcbnew")
	(generator_version "10.0")
	(general
		(thickness 1.6)
		(legacy_teardrops no)
	)
	(paper "A4")
	(title_block
		(title "timecard-production-celestica-r4006 — R4006-B0001-02_R01.brd")
		(comment 1 "Time Appliance Project (Time Card) / footprints 282-283 of 1113")
	)
	(layers
		(0 "F.Cu" signal "TOP")
		(4 "In1.Cu" signal "L02_GND1")
		(6 "In2.Cu" signal "L03_SIG1")
		(8 "In3.Cu" signal "L04_GND2")
		(10 "In4.Cu" signal "L05_VCC1")
		(12 "In5.Cu" signal "L06_VCC2")
		(14 "In6.Cu" signal "L07_GND3")
		(16 "In7.Cu" signal "L08_SIG2")
		(18 "In8.Cu" signal "L09_GND4")
		(2 "B.Cu" signal "BOTTOM")
		(9 "F.Adhes" user "F.Adhesive")
		(11 "B.Adhes" user "B.Adhesive")
		(13 "F.Paste" user "Package Geometry/Pastemask Top")
		(15 "B.Paste" user "Package Geometry/Pastemask Bottom")
		(5 "F.SilkS" user "Ref Des/Silkscreen Top")
		(7 "B.SilkS" user "Ref Des/Silkscreen Bottom")
		(1 "F.Mask" user "Board Geometry/Soldermask Top")
		(3 "B.Mask" user "Board Geometry/Soldermask Bottom")
		(17 "Dwgs.User" user "User.Drawings")
		(19 "Cmts.User" user "User.Comments")
		(21 "Eco1.User" user "User.Eco1")
		(23 "Eco2.User" user "User.Eco2")
		(25 "Edge.Cuts" user "Board Geometry/Outline")
		(27 "Margin" user)
		(31 "F.CrtYd" user "Package Geometry/Place Bound Top")
		(29 "B.CrtYd" user "Package Geometry/Place Bound Bottom")
		(35 "F.Fab" user "Ref Des/Assembly Top")
		(33 "B.Fab" user "Ref Des/Assembly Bottom")
	)
	(footprint ""
		(layer "F.Cu")
		(at 103.632 -24.638)
		(property "Reference" "R242"
			(at -10.033 0.16637 0)
			(unlocked yes)
			(layer "F.SilkS")
			(effects
				(font
					(size 0.7874 0.5842)
					(thickness 0.1524)
				)
			)
		)
		(property "Value" "VAL*"
			(at 0.02032 2.13233 0)
			(unlocked yes)
			(layer "F.Fab")
			(hide yes)
			(effects
				(font
					(size 0.7874 0.5842)
					(thickness 0.1524)
				)
			)
		)
		(property "Tolerance" "TOL*"
			(at 0.044704 3.05435 0)
			(unlocked yes)
			(layer "Cmts.User")
			(hide yes)
			(effects
				(font
					(size 0.7874 0.5842)
					(thickness 0.1524)
				)
			)
		)
		(property "User Part Number" "PARTNUM*"
			(at 0.02032 4.024884 0)
			(unlocked yes)
			(layer "Cmts.User")
			(hide yes)
			(effects
				(font
					(size 0.7874 0.5842)
					(thickness 0.1524)
				)
			)
		)
		(property "Device Type" "RESISTOR-G155-11500-01,150OHM,A"
			(at 0.008382 1.210564 0)
			(unlocked yes)
			(layer "F.Fab")
			(hide yes)
			(effects
				(font
					(size 0.7874 0.5842)
					(thickness 0.1524)
				)
			)
		)
		(duplicate_pad_numbers_are_jumpers no)
		(fp_line
			(start -1.143 -0.5588)
			(end -1.143 0.5588)
			(stroke
				(width 0.1)
				(type default)
			)
			(layer "F.SilkS")
		)
		(fp_line
			(start -1.143 0.5588)
			(end 1.143 0.5588)
			(stroke
				(width 0.1)
				(type default)
			)
			(layer "F.SilkS")
		)
		(fp_line
			(start 1.143 -0.5588)
			(end -1.143 -0.5588)
			(stroke
				(width 0.1)
				(type default)
			)
			(layer "F.SilkS")
		)
		(fp_line
			(start 1.143 0.5588)
			(end 1.143 -0.5588)
			(stroke
				(width 0.1)
				(type default)
			)
			(layer "F.SilkS")
		)
		(fp_rect
			(start -1.143 0.5588)
			(end 1.143 -0.5588)
			(stroke
				(width 0)
				(type default)
			)
			(fill no)
			(layer "F.CrtYd")
		)
		(fp_line
			(start -0.508 -0.3048)
			(end -0.508 0.3048)
			(stroke
				(width 0.1)
				(type default)
			)
			(layer "F.Fab")
		)
		(fp_line
			(start -0.508 0.3048)
			(end 0.508 0.3048)
			(stroke
				(width 0.1)
				(type default)
			)
			(layer "F.Fab")
		)
		(fp_line
			(start 0.508 -0.3048)
			(end -0.508 -0.3048)
			(stroke
				(width 0.1)
				(type default)
			)
			(layer "F.Fab")
		)
		(fp_line
			(start 0.508 0.3048)
			(end 0.508 -0.3048)
			(stroke
				(width 0.1)
				(type default)
			)
			(layer "F.Fab")
		)
		(pad "1" smd rect
			(at -0.5334 0)
			(size 0.7112 0.6096)
			(layers "F.Cu" "F.Mask" "F.Paste")
			(net "OSC_125M_CLKP")
		)
		(pad "2" smd rect
			(at 0.5334 0)
			(size 0.7112 0.6096)
			(layers "F.Cu" "F.Mask" "F.Paste")
			(net "SG")
		)
		(zone
			(layer "F.Cu")
			(hatch none 0.5)
			(connect_pads
				(clearance 0)
			)
			(min_thickness 0.25)
			(keepout
				(tracks allowed)
				(vias not_allowed)
				(pads allowed)
				(copperpour not_allowed)
				(footprints allowed)
			)
			(placement
				(enabled no)
				(sheetname "")
			)
			(fill
				(thermal_gap 0.5)
				(thermal_bridge_width 0.5)
				(island_removal_mode 0)
			)
			(polygon
				(pts
					(xy 103.5558 -24.3332) (xy 103.7082 -24.3332) (xy 103.7082 -24.9428) (xy 103.5558 -24.9428)
				)
			)
		)
	)
	(footprint ""
		(layer "F.Cu")
		(at 31.115 -96.266)
		(property "Reference" "C87"
			(at 3.08737 1.016 90)
			(unlocked yes)
			(layer "F.SilkS")
			(effects
				(font
					(size 0.7874 0.5842)
					(thickness 0.1524)
				)
			)
		)
		(property "Value" "VAL*"
			(at 0.193548 2.13614 0)
			(unlocked yes)
			(layer "F.Fab")
			(hide yes)
			(effects
				(font
					(size 0.7874 0.5842)
					(thickness 0.1524)
				)
			)
		)
		(property "Tolerance" "TOL*"
			(at 0.216154 3.1496 0)
			(unlocked yes)
			(layer "Cmts.User")
			(hide yes)
			(effects
				(font
					(size 0.7874 0.5842)
					(thickness 0.1524)
				)
			)
		)
		(property "Device Type" "CAPACITOR-G104-0A180-FJ,18PF,5%"
			(at 0.184404 1.180592 0)
			(unlocked yes)
			(layer "F.Fab")
			(hide yes)
			(effects
				(font
					(size 0.7874 0.5842)
					(thickness 0.1524)
				)
			)
		)
		(property "User Part Number" "PARTNUM*"
			(at 0.216154 4.185666 0)
			(unlocked yes)
			(layer "Cmts.User")
			(hide yes)
			(effects
				(font
					(size 0.7874 0.5842)
					(thickness 0.1524)
				)
			)
		)
		(duplicate_pad_numbers_are_jumpers no)
		(fp_line
			(start -0.671322 -0.4445)
			(end 0.671322 -0.4445)
			(stroke
				(width 0.1)
				(type default)
			)
			(layer "F.SilkS")
		)
		(fp_line
			(start -0.671322 0.4445)
			(end -0.671322 -0.4445)
			(stroke
				(width 0.1)
				(type default)
			)
			(layer "F.SilkS")
		)
		(fp_line
			(start 0.671322 -0.4445)
			(end 0.671322 0.4445)
			(stroke
				(width 0.1)
				(type default)
			)
			(layer "F.SilkS")
		)
		(fp_line
			(start 0.671322 0.4445)
			(end -0.671322 0.4445)
			(stroke
				(width 0.1)
				(type default)
			)
			(layer "F.SilkS")
		)
		(fp_rect
			(start -0.671322 -0.4445)
			(end 0.671322 0.4445)
			(stroke
				(width 0)
				(type default)
			)
			(fill no)
			(layer "F.CrtYd")
		)
		(fp_line
			(start -0.31496 -0.1651)
			(end -0.31496 0.1651)
			(stroke
				(width 0.1)
				(type default)
			)
			(layer "F.Fab")
		)
		(fp_line
			(start -0.31496 0.1651)
			(end 0.31496 0.1651)
			(stroke
				(width 0.1)
				(type default)
			)
			(layer "F.Fab")
		)
		(fp_line
			(start 0.31496 -0.1651)
			(end -0.31496 -0.1651)
			(stroke
				(width 0.1)
				(type default)
			)
			(layer "F.Fab")
		)
		(fp_line
			(start 0.31496 0.1651)
			(end 0.31496 -0.1651)
			(stroke
				(width 0.1)
				(type default)
			)
			(layer "F.Fab")
		)
		(pad "1" smd rect
			(at -0.264922 0)
			(size 0.3048 0.381)
			(layers "F.Cu" "F.Mask" "F.Paste")
			(net "SG")
		)
		(pad "2" smd rect
			(at 0.264922 0)
			(size 0.3048 0.381)
			(layers "F.Cu" "F.Mask" "F.Paste")
			(net "UNNAMED_524_CAPACITOR_I10_2")
		)
		(zone
			(layer "F.Cu")
			(hatch none 0.5)
			(connect_pads
				(clearance 0)
			)
			(min_thickness 0.25)
			(keepout
				(tracks allowed)
				(vias not_allowed)
				(pads allowed)
				(copperpour not_allowed)
				(footprints allowed)
			)
			(placement
				(enabled no)
				(sheetname "")
			)
			(fill
				(thermal_gap 0.5)
				(thermal_bridge_width 0.5)
				(island_removal_mode 0)
			)
			(polygon
				(pts
					(xy 31.002478 -96.4565) (xy 31.002478 -96.0755) (xy 31.227522 -96.0755) (xy 31.227522 -96.4565)
				)
			)
		)
	)
)
